(kicad_pcb
	(version 20260206)
	(generator "pcbnew")
	(generator_version "10.0")
	(general
		(thickness 1.6)
		(legacy_teardrops no)
	)
	(paper "A4")
	(title_block
		(title "01162023_DA0F0TEBIF0_F0T_Expander_BD_F_brd_V02_OCP.brd")
		(comment 1 "Grand Teton / footprints 3166-3170 of 9728")
	)
	(layers
		(0 "F.Cu" signal "TOP")
		(4 "In1.Cu" signal "GND")
		(6 "In2.Cu" signal "VCC")
		(8 "In3.Cu" signal "VCC1")
		(10 "In4.Cu" signal "GND1")
		(12 "In5.Cu" signal "IN1")
		(14 "In6.Cu" signal "GND2")
		(16 "In7.Cu" signal "IN2")
		(18 "In8.Cu" signal "GND3")
		(20 "In9.Cu" signal "IN3")
		(22 "In10.Cu" signal "GND4")
		(24 "In11.Cu" signal "IN4")
		(26 "In12.Cu" signal "GND5")
		(28 "In13.Cu" signal "IN5")
		(30 "In14.Cu" signal "GND6")
		(32 "In15.Cu" signal "IN6")
		(34 "In16.Cu" signal "GND7")
		(2 "B.Cu" signal "BOTTOM")
		(9 "F.Adhes" user "F.Adhesive")
		(11 "B.Adhes" user "B.Adhesive")
		(13 "F.Paste" user "Package Geometry/Pastemask Top")
		(15 "B.Paste" user "Package Geometry/Pastemask Bottom")
		(5 "F.SilkS" user "Ref Des/Silkscreen Top")
		(7 "B.SilkS" user "Ref Des/Silkscreen Bottom")
		(1 "F.Mask" user "Board Geometry/Soldermask Top")
		(3 "B.Mask" user "Board Geometry/Soldermask Bottom")
		(17 "Dwgs.User" user "User.Drawings")
		(19 "Cmts.User" user "User.Comments")
		(21 "Eco1.User" user "User.Eco1")
		(23 "Eco2.User" user "User.Eco2")
		(25 "Edge.Cuts" user "Board Geometry/Outline")
		(27 "Margin" user)
		(31 "F.CrtYd" user "Package Geometry/Place Bound Top")
		(29 "B.CrtYd" user "Package Geometry/Place Bound Bottom")
		(35 "F.Fab" user "Ref Des/Assembly Top")
		(33 "B.Fab" user "Ref Des/Assembly Bottom")
	)
	(footprint ""
		(layer "F.Cu")
		(at 328.106024 8.116824)
		(property "Reference" "DE14T_2"
			(at -3.6068 -2.962148 0)
			(unlocked yes)
			(layer "F.SilkS")
			(effects
				(font
					(size 0.7874 0.5842)
					(thickness 0.1524)
				)
				(justify left)
			)
		)
		(property "Value" ""
			(at 0 0 0)
			(layer "F.Fab")
			(effects
				(font
					(size 1.27 1.27)
				)
			)
		)
		(duplicate_pad_numbers_are_jumpers no)
		(fp_line
			(start -1.2192 -2.1082)
			(end 1.2192 -2.1082)
			(stroke
				(width 0.1524)
				(type default)
			)
			(layer "F.SilkS")
		)
		(fp_line
			(start -1.2192 2.1082)
			(end -1.2192 -2.1082)
			(stroke
				(width 0.1524)
				(type default)
			)
			(layer "F.SilkS")
		)
		(fp_line
			(start 1.2192 -2.1082)
			(end 1.2192 2.1082)
			(stroke
				(width 0.1524)
				(type default)
			)
			(layer "F.SilkS")
		)
		(fp_line
			(start 1.2192 2.1082)
			(end -1.2192 2.1082)
			(stroke
				(width 0.1524)
				(type default)
			)
			(layer "F.SilkS")
		)
		(pad "" np_thru_hole circle
			(at -2.8829 -1.27 270)
			(size 1.0414 1.0414)
			(drill 1.0414)
			(layers "*.Cu" "*.Mask")
			(clearance 0.381)
			(thermal_gap 0.381)
		)
		(pad "" np_thru_hole circle
			(at -2.8829 1.27 270)
			(size 1.0414 1.0414)
			(drill 1.0414)
			(layers "*.Cu" "*.Mask")
			(clearance 0.381)
			(thermal_gap 0.381)
		)
		(pad "" np_thru_hole circle
			(at 3.4671 -1.27 270)
			(size 1.0414 1.0414)
			(drill 1.0414)
			(layers "*.Cu" "*.Mask")
			(clearance 0.381)
			(thermal_gap 0.381)
		)
		(pad "" np_thru_hole circle
			(at 3.4671 1.27 270)
			(size 1.0414 1.0414)
			(drill 1.0414)
			(layers "*.Cu" "*.Mask")
			(clearance 0.381)
			(thermal_gap 0.381)
		)
		(pad "1" smd rect
			(at 0.8255 -0.249936 270)
			(size 0.3048 0.508)
			(layers "F.Cu" "F.Mask" "F.Paste")
			(net "85_10INCH_IN2_DN")
		)
		(pad "2" smd rect
			(at 0.8255 0.249936 270)
			(size 0.3048 0.508)
			(layers "F.Cu" "F.Mask" "F.Paste")
			(net "85_10INCH_IN2_DP")
		)
		(pad "3" smd circle
			(at 0 0)
			(size 0 0)
			(layers "F.Cu" "F.Mask" "F.Paste")
			(net "COUPON_GND2")
		)
		(zone
			(layer "F.Cu")
			(hatch none 0.5)
			(connect_pads
				(clearance 0)
			)
			(min_thickness 0.25)
			(keepout
				(tracks not_allowed)
				(vias allowed)
				(pads allowed)
				(copperpour not_allowed)
				(footprints allowed)
			)
			(placement
				(enabled no)
				(sheetname "")
			)
			(fill
				(thermal_gap 0.5)
				(thermal_bridge_width 0.5)
				(island_removal_mode 0)
			)
			(polygon
				(pts
					(xy 329.223624 7.568184) (xy 329.223624 7.663688) (xy 328.626724 7.663688) (xy 328.626724 8.070088)
					(xy 329.223624 8.070088) (xy 329.223624 8.16356) (xy 328.626724 8.16356) (xy 328.626724 8.56996)
					(xy 329.223624 8.56996) (xy 329.223624 8.665464) (xy 328.525124 8.665464) (xy 328.525124 7.568184)
				)
			)
		)
		(zone
			(layers "F.Cu" "B.Cu" "In1.Cu" "In2.Cu" "In3.Cu" "In4.Cu" "In5.Cu" "In6.Cu"
				"In7.Cu" "In8.Cu" "In9.Cu" "In10.Cu" "In11.Cu" "In12.Cu" "In13.Cu" "In14.Cu"
				"In15.Cu" "In16.Cu"
			)
			(hatch none 0.5)
			(connect_pads
				(clearance 0)
			)
			(min_thickness 0.25)
			(keepout
				(tracks not_allowed)
				(vias allowed)
				(pads allowed)
				(copperpour not_allowed)
				(footprints allowed)
			)
			(placement
				(enabled no)
				(sheetname "")
			)
			(fill
				(thermal_gap 0.5)
				(thermal_bridge_width 0.5)
				(island_removal_mode 0)
			)
			(polygon
				(pts
					(arc
						(start 326.150224 6.846824)
						(mid 324.296024 6.846824)
						(end 326.150224 6.846824)
					)
				)
			)
		)
		(zone
			(layers "F.Cu" "B.Cu" "In1.Cu" "In2.Cu" "In3.Cu" "In4.Cu" "In5.Cu" "In6.Cu"
				"In7.Cu" "In8.Cu" "In9.Cu" "In10.Cu" "In11.Cu" "In12.Cu" "In13.Cu" "In14.Cu"
				"In15.Cu" "In16.Cu"
			)
			(hatch none 0.5)
			(connect_pads
				(clearance 0)
			)
			(min_thickness 0.25)
			(keepout
				(tracks not_allowed)
				(vias allowed)
				(pads allowed)
				(copperpour not_allowed)
				(footprints allowed)
			)
			(placement
				(enabled no)
				(sheetname "")
			)
			(fill
				(thermal_gap 0.5)
				(thermal_bridge_width 0.5)
				(island_removal_mode 0)
			)
			(polygon
				(pts
					(arc
						(start 326.150224 9.386824)
						(mid 324.296024 9.386824)
						(end 326.150224 9.386824)
					)
				)
			)
		)
		(zone
			(layers "F.Cu" "B.Cu" "In1.Cu" "In2.Cu" "In3.Cu" "In4.Cu" "In5.Cu" "In6.Cu"
				"In7.Cu" "In8.Cu" "In9.Cu" "In10.Cu" "In11.Cu" "In12.Cu" "In13.Cu" "In14.Cu"
				"In15.Cu" "In16.Cu"
			)
			(hatch none 0.5)
			(connect_pads
				(clearance 0)
			)
			(min_thickness 0.25)
			(keepout
				(tracks not_allowed)
				(vias allowed)
				(pads allowed)
				(copperpour not_allowed)
				(footprints allowed)
			)
			(placement
				(enabled no)
				(sheetname "")
			)
			(fill
				(thermal_gap 0.5)
				(thermal_bridge_width 0.5)
				(island_removal_mode 0)
			)
			(polygon
				(pts
					(arc
						(start 332.500224 6.846824)
						(mid 330.646024 6.846824)
						(end 332.500224 6.846824)
					)
				)
			)
		)
		(zone
			(layers "F.Cu" "B.Cu" "In1.Cu" "In2.Cu" "In3.Cu" "In4.Cu" "In5.Cu" "In6.Cu"
				"In7.Cu" "In8.Cu" "In9.Cu" "In10.Cu" "In11.Cu" "In12.Cu" "In13.Cu" "In14.Cu"
				"In15.Cu" "In16.Cu"
			)
			(hatch none 0.5)
			(connect_pads
				(clearance 0)
			)
			(min_thickness 0.25)
			(keepout
				(tracks not_allowed)
				(vias allowed)
				(pads allowed)
				(copperpour not_allowed)
				(footprints allowed)
			)
			(placement
				(enabled no)
				(sheetname "")
			)
			(fill
				(thermal_gap 0.5)
				(thermal_bridge_width 0.5)
				(island_removal_mode 0)
			)
			(polygon
				(pts
					(arc
						(start 332.500224 9.386824)
						(mid 330.646024 9.386824)
						(end 332.500224 9.386824)
					)
				)
			)
		)
	)
	(footprint ""
		(layer "F.Cu")
		(at 228.161088 -37.951156)
		(property "Reference" "Q224"
			(at 0.403352 -2.925064 0)
			(unlocked yes)
			(layer "F.SilkS")
			(effects
				(font
					(size 0.7874 0.5842)
					(thickness 0.1524)
				)
			)
		)
		(property "Value" ""
			(at 0 0 0)
			(layer "F.Fab")
			(effects
				(font
					(size 1.27 1.27)
				)
			)
		)
		(duplicate_pad_numbers_are_jumpers no)
		(fp_line
			(start -1.376172 -1.199896)
			(end -0.508 -1.199896)
			(stroke
				(width 0.1524)
				(type default)
			)
			(layer "F.SilkS")
		)
		(fp_line
			(start -1.376172 1.199896)
			(end -1.376172 -1.199896)
			(stroke
				(width 0.1524)
				(type default)
			)
			(layer "F.SilkS")
		)
		(fp_line
			(start -0.508 -1.199896)
			(end 0 -0.762)
			(stroke
				(width 0.1524)
				(type default)
			)
			(layer "F.SilkS")
		)
		(fp_line
			(start 0 -0.762)
			(end 0.508 -1.199896)
			(stroke
				(width 0.1524)
				(type default)
			)
			(layer "F.SilkS")
		)
		(fp_line
			(start 0.508 -1.199896)
			(end 1.376172 -1.199896)
			(stroke
				(width 0.1524)
				(type default)
			)
			(layer "F.SilkS")
		)
		(fp_line
			(start 1.376172 -1.199896)
			(end 1.376172 1.199896)
			(stroke
				(width 0.1524)
				(type default)
			)
			(layer "F.SilkS")
		)
		(fp_line
			(start 1.376172 1.199896)
			(end -1.376172 1.199896)
			(stroke
				(width 0.1524)
				(type default)
			)
			(layer "F.SilkS")
		)
		(fp_poly
			(pts
				(xy -1.40716 -1.405636) (xy -1.6764 -2.213864) (xy -2.215388 -1.674876)
			)
			(stroke
				(width 0)
				(type default)
			)
			(fill yes)
			(layer "F.SilkS")
		)
		(fp_line
			(start -0.674878 -1.100074)
			(end 0.674878 -1.100074)
			(stroke
				(width 0.1)
				(type default)
			)
			(layer "F.Fab")
		)
		(fp_line
			(start -0.674878 1.100074)
			(end -0.674878 -1.100074)
			(stroke
				(width 0.1)
				(type default)
			)
			(layer "F.Fab")
		)
		(fp_line
			(start 0.674878 -1.100074)
			(end 0.674878 1.100074)
			(stroke
				(width 0.1)
				(type default)
			)
			(layer "F.Fab")
		)
		(fp_line
			(start 0.674878 1.100074)
			(end -0.674878 1.100074)
			(stroke
				(width 0.1)
				(type default)
			)
			(layer "F.Fab")
		)
		(fp_poly
			(pts
				(xy -1.4605 -0.7493) (xy -2.2225 -1.1303) (xy -2.2225 -0.3683)
			)
			(stroke
				(width 0)
				(type default)
			)
			(fill yes)
			(layer "F.Fab")
		)
		(pad "1" smd rect
			(at -0.899922 -0.750062 270)
			(size 0.6096 0.6096)
			(layers "F.Cu" "F.Mask" "F.Paste")
			(net "GND")
		)
		(pad "2" smd rect
			(at -0.899922 0 270)
			(size 0.4064 0.6096)
			(layers "F.Cu" "F.Mask" "F.Paste")
			(net "P3V3_SSD8_PG_G1")
		)
		(pad "3" smd rect
			(at -0.899922 0.750062 270)
			(size 0.6096 0.6096)
			(layers "F.Cu" "F.Mask" "F.Paste")
			(net "PWRGD_P3V3_SSD8_D")
		)
		(pad "4" smd rect
			(at 0.899922 0.750062 270)
			(size 0.6096 0.6096)
			(layers "F.Cu" "F.Mask" "F.Paste")
			(net "GND")
		)
		(pad "5" smd rect
			(at 0.899922 0 270)
			(size 0.4064 0.6096)
			(layers "F.Cu" "F.Mask" "F.Paste")
			(net "P3V3_SSD8_PG_G2")
		)
		(pad "6" smd rect
			(at 0.899922 -0.750062 270)
			(size 0.6096 0.6096)
			(layers "F.Cu" "F.Mask" "F.Paste")
			(net "P3V3_SSD8_PG_G2")
		)
	)
	(footprint ""
		(layer "F.Cu")
		(at 93.142562 -70.844918 -90)
		(property "Reference" "PD91"
			(at 3.890518 2.158492 90)
			(unlocked yes)
			(layer "F.SilkS")
			(effects
				(font
					(size 0.7874 0.5842)
					(thickness 0.1524)
				)
				(justify left)
			)
		)
		(property "Value" ""
			(at 0 0 270)
			(layer "F.Fab")
			(effects
				(font
					(size 1.27 1.27)
				)
			)
		)
		(duplicate_pad_numbers_are_jumpers no)
		(fp_line
			(start -3.400044 1.459992)
			(end -3.400044 -1.459992)
			(stroke
				(width 0.1524)
				(type default)
			)
			(layer "F.SilkS")
		)
		(fp_line
			(start 4.107942 1.459992)
			(end -3.400044 1.459992)
			(stroke
				(width 0.1524)
				(type default)
			)
			(layer "F.SilkS")
		)
		(fp_line
			(start -3.400044 -1.459992)
			(end 4.107942 -1.459992)
			(stroke
				(width 0.1524)
				(type default)
			)
			(layer "F.SilkS")
		)
		(fp_line
			(start 4.107942 -1.459992)
			(end 4.107942 1.459992)
			(stroke
				(width 0.1524)
				(type default)
			)
			(layer "F.SilkS")
		)
		(fp_poly
			(pts
				(xy 4.107942 -1.459992) (xy 4.107942 1.459992) (xy 3.308096 1.459992) (xy 3.308096 -1.459992)
			)
			(stroke
				(width 0)
				(type default)
			)
			(fill yes)
			(layer "F.SilkS")
		)
		(fp_line
			(start -2.29997 1.459992)
			(end -2.29997 -1.459992)
			(stroke
				(width 0.1)
				(type default)
			)
			(layer "F.Fab")
		)
		(fp_line
			(start 2.29997 1.459992)
			(end -2.29997 1.459992)
			(stroke
				(width 0.1)
				(type default)
			)
			(layer "F.Fab")
		)
		(fp_line
			(start -2.29997 -1.459992)
			(end 2.29997 -1.459992)
			(stroke
				(width 0.1)
				(type default)
			)
			(layer "F.Fab")
		)
		(fp_line
			(start 2.29997 -1.459992)
			(end 2.29997 1.459992)
			(stroke
				(width 0.1)
				(type default)
			)
			(layer "F.Fab")
		)
		(fp_text user "-"
			(at 5.4102 0.29845 90)
			(unlocked yes)
			(layer "F.SilkS")
			(effects
				(font
					(size 1.905 1.4224)
					(thickness 0.1524)
				)
				(justify left)
			)
		)
		(fp_text user "+"
			(at -5.202682 -0.214376 270)
			(unlocked yes)
			(layer "F.SilkS")
			(effects
				(font
					(size 1.905 1.4224)
					(thickness 0.1524)
				)
				(justify left)
			)
		)
		(fp_text user "-"
			(at 5.4102 0.29845 90)
			(unlocked yes)
			(layer "F.Fab")
			(effects
				(font
					(size 1.905 1.4224)
					(thickness 0.1524)
				)
				(justify left)
			)
		)
		(fp_text user "+"
			(at -4.7752 -0.12065 270)
			(unlocked yes)
			(layer "F.Fab")
			(effects
				(font
					(size 1.905 1.4224)
					(thickness 0.1524)
				)
				(justify left)
			)
		)
		(pad "A" smd rect
			(at -1.999996 0)
			(size 1.7018 2.5146)
			(layers "F.Cu" "F.Mask" "F.Paste")
			(net "GND")
		)
		(pad "C" smd rect
			(at 1.999996 0)
			(size 1.7018 2.5146)
			(layers "F.Cu" "F.Mask" "F.Paste")
			(net "P12V_SSD3_R")
		)
	)
	(footprint ""
		(layer "F.Cu")
		(at 387.580632 -103.803196)
		(property "Reference" "C693"
			(at 0 0 0)
			(layer "F.SilkS")
			(hide yes)
			(effects
				(font
					(size 1.27 1.27)
				)
			)
		)
		(property "Value" ""
			(at 0 0 0)
			(layer "F.Fab")
			(effects
				(font
					(size 1.27 1.27)
				)
			)
		)
		(duplicate_pad_numbers_are_jumpers no)
		(fp_line
			(start -0.299974 -0.150114)
			(end 0.299974 -0.150114)
			(stroke
				(width 0.1)
				(type default)
			)
			(layer "F.Fab")
		)
		(fp_line
			(start -0.299974 0.150114)
			(end -0.299974 -0.150114)
			(stroke
				(width 0.1)
				(type default)
			)
			(layer "F.Fab")
		)
		(fp_line
			(start 0.299974 -0.150114)
			(end 0.299974 0.150114)
			(stroke
				(width 0.1)
				(type default)
			)
			(layer "F.Fab")
		)
		(fp_line
			(start 0.299974 0.150114)
			(end -0.299974 0.150114)
			(stroke
				(width 0.1)
				(type default)
			)
			(layer "F.Fab")
		)
		(pad "1" smd rect
			(at -0.2667 0)
			(size 0.3048 0.381)
			(layers "F.Cu" "F.Mask" "F.Paste")
			(net "P5E_PEX3_STN1_TX_DN<18>")
		)
		(pad "2" smd rect
			(at 0.2667 0)
			(size 0.3048 0.381)
			(layers "F.Cu" "F.Mask" "F.Paste")
			(net "P5E_PEX3_STN1_TX_C_DN<18>")
		)
	)
	(footprint ""
		(layer "F.Cu")
		(at 421.247316 -19.33956)
		(property "Reference" "C3975"
			(at 0 0 0)
			(layer "F.SilkS")
			(hide yes)
			(effects
				(font
					(size 1.27 1.27)
				)
			)
		)
		(property "Value" ""
			(at 0 0 0)
			(layer "F.Fab")
			(effects
				(font
					(size 1.27 1.27)
				)
			)
		)
		(duplicate_pad_numbers_are_jumpers no)
		(fp_line
			(start -0.7874 -0.4064)
			(end 0.7874 -0.4064)
			(stroke
				(width 0.1524)
				(type default)
			)
			(layer "F.SilkS")
		)
		(fp_line
			(start -0.7874 0.4064)
			(end -0.7874 -0.4064)
			(stroke
				(width 0.1524)
				(type default)
			)
			(layer "F.SilkS")
		)
		(fp_line
			(start 0.7874 -0.4064)
			(end 0.7874 0.4064)
			(stroke
				(width 0.1524)
				(type default)
			)
			(layer "F.SilkS")
		)
		(fp_line
			(start 0.7874 0.4064)
			(end -0.7874 0.4064)
			(stroke
				(width 0.1524)
				(type default)
			)
			(layer "F.SilkS")
		)
		(fp_line
			(start -0.67945 -0.305054)
			(end -0.12065 -0.305054)
			(stroke
				(width 0.1)
				(type default)
			)
			(layer "F.Fab")
		)
		(fp_line
			(start -0.67945 0.3048)
			(end -0.67945 -0.305054)
			(stroke
				(width 0.1)
				(type default)
			)
			(layer "F.Fab")
		)
		(fp_line
			(start -0.12065 -0.305054)
			(end -0.12065 -0.2794)
			(stroke
				(width 0.1)
				(type default)
			)
			(layer "F.Fab")
		)
		(fp_line
			(start -0.12065 -0.2794)
			(end 0.12065 -0.2794)
			(stroke
				(width 0.1)
				(type default)
			)
			(layer "F.Fab")
		)
		(fp_line
			(start -0.12065 0.2794)
			(end -0.12065 0.3048)
			(stroke
				(width 0.1)
				(type default)
			)
			(layer "F.Fab")
		)
		(fp_line
			(start -0.12065 0.3048)
			(end -0.67945 0.3048)
			(stroke
				(width 0.1)
				(type default)
			)
			(layer "F.Fab")
		)
		(fp_line
			(start 0.120396 0.2794)
			(end -0.12065 0.2794)
			(stroke
				(width 0.1)
				(type default)
			)
			(layer "F.Fab")
		)
		(fp_line
			(start 0.120396 0.3048)
			(end 0.120396 0.2794)
			(stroke
				(width 0.1)
				(type default)
			)
			(layer "F.Fab")
		)
		(fp_line
			(start 0.12065 -0.3048)
			(end 0.67945 -0.3048)
			(stroke
				(width 0.1)
				(type default)
			)
			(layer "F.Fab")
		)
		(fp_line
			(start 0.12065 -0.2794)
			(end 0.12065 -0.3048)
			(stroke
				(width 0.1)
				(type default)
			)
			(layer "F.Fab")
		)
		(fp_line
			(start 0.67945 -0.3048)
			(end 0.67945 0.3048)
			(stroke
				(width 0.1)
				(type default)
			)
			(layer "F.Fab")
		)
		(fp_line
			(start 0.67945 0.3048)
			(end 0.120396 0.3048)
			(stroke
				(width 0.1)
				(type default)
			)
			(layer "F.Fab")
		)
		(pad "1" smd circle
			(at -0.40005 0)
			(size 0 0)
			(layers "F.Cu" "F.Mask" "F.Paste")
			(net "P12V_SSD14")
		)
		(pad "2" smd circle
			(at 0.40005 0)
			(size 0 0)
			(layers "F.Cu" "F.Mask" "F.Paste")
			(net "GND")
		)
	)
)
